# S9S_MB_2U (Grand Teton) — schematic netlist excerpt (pin names and nets, part order shuffled) for the footprints in the layout excerpt that follows; sources: Cadence DE-HDL packaged netlist, KiCad conversion of 03242023_DA0F0TMBIJ0_F0T_Motherboard_J_brd_V01_OCP.brd

PC447  Q_CAP  100NF 50V 10% X7R  pkg C0402  page 293 : A = SW_PVCCINFAON_CPU1_BOOT2_R ; B = SW_PVCCINFAON_CPU1_BOOTR2
R4673  Q_RES  0 5% EMPTY  pkg 0402LF  page 306 : A = A_HSC_LOW_GATE ; B = GND

(kicad_pcb
	(version 20260206)
	(generator "pcbnew")
	(generator_version "10.0")
	(general
		(thickness 1.6)
		(legacy_teardrops no)
	)
	(paper "A4")
	(title_block
		(title "03242023_DA0F0TMBIJ0_F0T_Motherboard_J_brd_V01_OCP.brd")
		(comment 1 "Grand Teton / footprints 3686-3687 of 6105")
	)
	(layers
		(0 "F.Cu" signal "TOP")
		(4 "In1.Cu" signal "GND")
		(6 "In2.Cu" signal "IN1")
		(8 "In3.Cu" signal "GND1")
		(10 "In4.Cu" signal "IN2")
		(12 "In5.Cu" signal "GND2")
		(14 "In6.Cu" signal "IN3")
		(16 "In7.Cu" signal "GND3")
		(18 "In8.Cu" signal "VCC")
		(20 "In9.Cu" signal "VCC1")
		(22 "In10.Cu" signal "GND4")
		(24 "In11.Cu" signal "IN4")
		(26 "In12.Cu" signal "GND5")
		(28 "In13.Cu" signal "IN5")
		(30 "In14.Cu" signal "GND6")
		(32 "In15.Cu" signal "IN6")
		(34 "In16.Cu" signal "GND7")
		(2 "B.Cu" signal "BOTTOM")
		(9 "F.Adhes" user "F.Adhesive")
		(11 "B.Adhes" user "B.Adhesive")
		(13 "F.Paste" user "Package Geometry/Pastemask Top")
		(15 "B.Paste" user "Package Geometry/Pastemask Bottom")
		(5 "F.SilkS" user "Ref Des/Silkscreen Top")
		(7 "B.SilkS" user "Ref Des/Silkscreen Bottom")
		(1 "F.Mask" user "Board Geometry/Soldermask Top")
		(3 "B.Mask" user "Board Geometry/Soldermask Bottom")
		(17 "Dwgs.User" user "User.Drawings")
		(19 "Cmts.User" user "User.Comments")
		(21 "Eco1.User" user "User.Eco1")
		(23 "Eco2.User" user "User.Eco2")
		(25 "Edge.Cuts" user "Board Geometry/Outline")
		(27 "Margin" user)
		(31 "F.CrtYd" user "Package Geometry/Place Bound Top")
		(29 "B.CrtYd" user "Package Geometry/Place Bound Bottom")
		(35 "F.Fab" user "Ref Des/Assembly Top")
		(33 "B.Fab" user "Ref Des/Assembly Bottom")
	)
	(footprint ""
		(layer "F.Cu")
		(at 50.437542 -149.575266)
		(property "Reference" "PC447"
			(at 0 0 0)
			(layer "F.SilkS")
			(hide yes)
			(effects
				(font
					(size 1.27 1.27)
				)
			)
		)
		(property "Value" ""
			(at 0 0 0)
			(layer "F.Fab")
			(effects
				(font
					(size 1.27 1.27)
				)
			)
		)
		(duplicate_pad_numbers_are_jumpers no)
		(fp_line
			(start -0.7874 -0.4064)
			(end 0.7874 -0.4064)
			(stroke
				(width 0.1524)
				(type default)
			)
			(layer "F.SilkS")
		)
		(fp_line
			(start -0.7874 0.4064)
			(end -0.7874 -0.4064)
			(stroke
				(width 0.1524)
				(type default)
			)
			(layer "F.SilkS")
		)
		(fp_line
			(start 0.7874 -0.4064)
			(end 0.7874 0.4064)
			(stroke
				(width 0.1524)
				(type default)
			)
			(layer "F.SilkS")
		)
		(fp_line
			(start 0.7874 0.4064)
			(end -0.7874 0.4064)
			(stroke
				(width 0.1524)
				(type default)
			)
			(layer "F.SilkS")
		)
		(fp_line
			(start -0.67945 -0.305054)
			(end -0.12065 -0.305054)
			(stroke
				(width 0.1)
				(type default)
			)
			(layer "F.Fab")
		)
		(fp_line
			(start -0.67945 0.3048)
			(end -0.67945 -0.305054)
			(stroke
				(width 0.1)
				(type default)
			)
			(layer "F.Fab")
		)
		(fp_line
			(start -0.12065 -0.305054)
			(end -0.12065 -0.2794)
			(stroke
				(width 0.1)
				(type default)
			)
			(layer "F.Fab")
		)
		(fp_line
			(start -0.12065 -0.2794)
			(end 0.12065 -0.2794)
			(stroke
				(width 0.1)
				(type default)
			)
			(layer "F.Fab")
		)
		(fp_line
			(start -0.12065 0.2794)
			(end -0.12065 0.3048)
			(stroke
				(width 0.1)
				(type default)
			)
			(layer "F.Fab")
		)
		(fp_line
			(start -0.12065 0.3048)
			(end -0.67945 0.3048)
			(stroke
				(width 0.1)
				(type default)
			)
			(layer "F.Fab")
		)
		(fp_line
			(start 0.120396 0.2794)
			(end -0.12065 0.2794)
			(stroke
				(width 0.1)
				(type default)
			)
			(layer "F.Fab")
		)
		(fp_line
			(start 0.120396 0.3048)
			(end 0.120396 0.2794)
			(stroke
				(width 0.1)
				(type default)
			)
			(layer "F.Fab")
		)
		(fp_line
			(start 0.12065 -0.3048)
			(end 0.67945 -0.3048)
			(stroke
				(width 0.1)
				(type default)
			)
			(layer "F.Fab")
		)
		(fp_line
			(start 0.12065 -0.2794)
			(end 0.12065 -0.3048)
			(stroke
				(width 0.1)
				(type default)
			)
			(layer "F.Fab")
		)
		(fp_line
			(start 0.67945 -0.3048)
			(end 0.67945 0.3048)
			(stroke
				(width 0.1)
				(type default)
			)
			(layer "F.Fab")
		)
		(fp_line
			(start 0.67945 0.3048)
			(end 0.120396 0.3048)
			(stroke
				(width 0.1)
				(type default)
			)
			(layer "F.Fab")
		)
		(pad "1" smd circle
			(at -0.40005 0)
			(size 0 0)
			(layers "F.Cu" "F.Mask" "F.Paste")
			(net "SW_PVCCINFAON_CPU1_BOOT2_R")
		)
		(pad "2" smd circle
			(at 0.40005 0)
			(size 0 0)
			(layers "F.Cu" "F.Mask" "F.Paste")
			(net "SW_PVCCINFAON_CPU1_BOOTR2")
		)
	)
	(footprint ""
		(layer "F.Cu")
		(at 278.246078 -417.2839 -90)
		(property "Reference" "R4673"
			(at 0 0 270)
			(layer "F.SilkS")
			(hide yes)
			(effects
				(font
					(size 1.27 1.27)
				)
			)
		)
		(property "Value" ""
			(at 0 0 270)
			(layer "F.Fab")
			(effects
				(font
					(size 1.27 1.27)
				)
			)
		)
		(duplicate_pad_numbers_are_jumpers no)
		(fp_line
			(start -0.7874 0.4064)
			(end -0.7874 -0.4064)
			(stroke
				(width 0.1524)
				(type default)
			)
			(layer "F.SilkS")
		)
		(fp_line
			(start 0.7874 0.4064)
			(end -0.7874 0.4064)
			(stroke
				(width 0.1524)
				(type default)
			)
			(layer "F.SilkS")
		)
		(fp_line
			(start -0.7874 -0.4064)
			(end 0.7874 -0.4064)
			(stroke
				(width 0.1524)
				(type default)
			)
			(layer "F.SilkS")
		)
		(fp_line
			(start 0.7874 -0.4064)
			(end 0.7874 0.4064)
			(stroke
				(width 0.1524)
				(type default)
			)
			(layer "F.SilkS")
		)
		(fp_line
			(start -0.67945 0.3048)
			(end -0.67945 -0.305054)
			(stroke
				(width 0.1)
				(type default)
			)
			(layer "F.Fab")
		)
		(fp_line
			(start -0.12065 0.3048)
			(end -0.67945 0.3048)
			(stroke
				(width 0.1)
				(type default)
			)
			(layer "F.Fab")
		)
		(fp_line
			(start 0.120396 0.3048)
			(end 0.120396 0.2794)
			(stroke
				(width 0.1)
				(type default)
			)
			(layer "F.Fab")
		)
		(fp_line
			(start 0.67945 0.3048)
			(end 0.120396 0.3048)
			(stroke
				(width 0.1)
				(type default)
			)
			(layer "F.Fab")
		)
		(fp_line
			(start -0.12065 0.2794)
			(end -0.12065 0.3048)
			(stroke
				(width 0.1)
				(type default)
			)
			(layer "F.Fab")
		)
		(fp_line
			(start 0.120396 0.2794)
			(end -0.12065 0.2794)
			(stroke
				(width 0.1)
				(type default)
			)
			(layer "F.Fab")
		)
		(fp_line
			(start -0.12065 -0.2794)
			(end 0.12065 -0.2794)
			(stroke
				(width 0.1)
				(type default)
			)
			(layer "F.Fab")
		)
		(fp_line
			(start 0.12065 -0.2794)
			(end 0.12065 -0.3048)
			(stroke
				(width 0.1)
				(type default)
			)
			(layer "F.Fab")
		)
		(fp_line
			(start 0.12065 -0.3048)
			(end 0.67945 -0.3048)
			(stroke
				(width 0.1)
				(type default)
			)
			(layer "F.Fab")
		)
		(fp_line
			(start 0.67945 -0.3048)
			(end 0.67945 0.3048)
			(stroke
				(width 0.1)
				(type default)
			)
			(layer "F.Fab")
		)
		(fp_line
			(start -0.67945 -0.305054)
			(end -0.12065 -0.305054)
			(stroke
				(width 0.1)
				(type default)
			)
			(layer "F.Fab")
		)
		(fp_line
			(start -0.12065 -0.305054)
			(end -0.12065 -0.2794)
			(stroke
				(width 0.1)
				(type default)
			)
			(layer "F.Fab")
		)
		(pad "1" smd circle
			(at -0.40005 0 270)
			(size 0 0)
			(layers "F.Cu" "F.Mask" "F.Paste")
			(net "A_HSC_LOW_GATE")
		)
		(pad "2" smd circle
			(at 0.40005 0 270)
			(size 0 0)
			(layers "F.Cu" "F.Mask" "F.Paste")
			(net "GND")
		)
	)
)
